(kicad_pcb
	(version 20241229)
	(generator "pcbnew")
	(generator_version "9.0")
	(general
		(thickness 1.711)
		(legacy_teardrops no)
	)
	(paper "A4")
	(title_block
		(title "Antmicro Baseboard for Jetson AGX Thor")
		(date "2026-02-18")
		(rev "1.1.0")
		(company "Antmicro Ltd")
		(comment 1 "www.antmicro.com")
		(comment 9 "footprints 51-55 of 1170")
	)
	(layers
		(0 "F.Cu" signal)
		(4 "In1.Cu" signal)
		(6 "In2.Cu" signal)
		(8 "In3.Cu" signal)
		(10 "In4.Cu" jumper)
		(12 "In5.Cu" signal)
		(14 "In6.Cu" signal)
		(16 "In7.Cu" signal)
		(18 "In8.Cu" signal)
		(2 "B.Cu" signal)
		(9 "F.Adhes" user "F.Adhesive")
		(11 "B.Adhes" user "B.Adhesive")
		(13 "F.Paste" user)
		(15 "B.Paste" user)
		(5 "F.SilkS" user "F.Silkscreen")
		(7 "B.SilkS" user "B.Silkscreen")
		(1 "F.Mask" user)
		(3 "B.Mask" user)
		(17 "Dwgs.User" user "User.Drawings")
		(19 "Cmts.User" user "User.Comments")
		(21 "Eco1.User" user "User.Eco1")
		(23 "Eco2.User" user "User.Eco2")
		(25 "Edge.Cuts" user)
		(27 "Margin" user)
		(31 "F.CrtYd" user "F.Courtyard")
		(29 "B.CrtYd" user "B.Courtyard")
		(35 "F.Fab" user)
		(33 "B.Fab" user)
	)
	(footprint "antmicro-footprints:C_0402_1005Metric"
		(layer "F.Cu")
		(at 219.564132 91.36)
		(descr "Capacitor SMD 0402")
		(tags "capacitor SMD 0402")
		(property "Reference" "C144"
			(at -1.71 -0.708 0)
			(layer "F.SilkS")
			(effects
				(font
					(size 0.7 0.7)
					(thickness 0.15)
				)
				(justify left bottom)
			)
		)
		(property "Value" "C_100n_0402"
			(at -1.022927 2.155213 0)
			(layer "F.Fab")
			(effects
				(font
					(size 0.7 0.7)
					(thickness 0.15)
				)
				(justify left bottom)
			)
		)
		(property "Datasheet" "https://www.murata.com/products/productdetail?partno=GRM155R61H104KE14%23"
			(at 0 0 0)
			(layer "F.Fab")
			(hide yes)
			(effects
				(font
					(size 1.27 1.27)
					(thickness 0.15)
				)
			)
		)
		(property "Description" "SMD Multilayer Ceramic Capacitor, 0.1 µF, 50 V, 0402 [1005 Metric], ± 10%, X5R, GRM Series"
			(at 0 0 0)
			(layer "F.Fab")
			(hide yes)
			(effects
				(font
					(size 1.27 1.27)
					(thickness 0.15)
				)
			)
		)
		(property "Manufacturer" "Murata"
			(at 0 0 0)
			(unlocked yes)
			(layer "F.Fab")
			(hide yes)
			(effects
				(font
					(size 1 1)
					(thickness 0.15)
				)
			)
		)
		(property "MPN" "GRM155R61H104KE14D"
			(at 0 0 0)
			(unlocked yes)
			(layer "F.Fab")
			(hide yes)
			(effects
				(font
					(size 1 1)
					(thickness 0.15)
				)
			)
		)
		(property "Val" "100n"
			(at 0 0 0)
			(unlocked yes)
			(layer "F.Fab")
			(hide yes)
			(effects
				(font
					(size 1 1)
					(thickness 0.15)
				)
			)
		)
		(property "License" "Apache-2.0"
			(at 0 0 0)
			(unlocked yes)
			(layer "F.Fab")
			(hide yes)
			(effects
				(font
					(size 1 1)
					(thickness 0.15)
				)
			)
		)
		(property "Author" "Antmicro"
			(at 0 0 0)
			(unlocked yes)
			(layer "F.Fab")
			(hide yes)
			(effects
				(font
					(size 1 1)
					(thickness 0.15)
				)
			)
		)
		(property "Voltage" "50V"
			(at 0 0 0)
			(unlocked yes)
			(layer "F.Fab")
			(hide yes)
			(effects
				(font
					(size 1 1)
					(thickness 0.15)
				)
			)
		)
		(property "Dielectric" "X5R"
			(at 0 0 0)
			(unlocked yes)
			(layer "F.Fab")
			(hide yes)
			(effects
				(font
					(size 1 1)
					(thickness 0.15)
				)
			)
		)
		(sheetname "/USB DP Alt mode/")
		(sheetfile "usb_dp.kicad_sch")
		(attr smd)
		(fp_rect
			(start -0.925 -0.47)
			(end 0.925 0.47)
			(stroke
				(width 0.05)
				(type default)
			)
			(fill no)
			(layer "F.CrtYd")
		)
		(fp_line
			(start -0.494 -0.25)
			(end 0.504 -0.25)
			(stroke
				(width 0.15)
				(type solid)
			)
			(layer "F.Fab")
		)
		(fp_line
			(start -0.494 0.248)
			(end -0.494 -0.25)
			(stroke
				(width 0.15)
				(type solid)
			)
			(layer "F.Fab")
		)
		(fp_line
			(start 0.504 -0.25)
			(end 0.504 0.248)
			(stroke
				(width 0.15)
				(type solid)
			)
			(layer "F.Fab")
		)
		(fp_line
			(start 0.504 0.248)
			(end -0.494 0.248)
			(stroke
				(width 0.15)
				(type solid)
			)
			(layer "F.Fab")
		)
		(fp_text user "Author: Antmicro"
			(at -0.939 3.399 0)
			(layer "F.Fab")
			(effects
				(font
					(size 0.7 0.7)
					(thickness 0.15)
				)
				(justify left bottom)
			)
		)
		(fp_text user "${REFERENCE}"
			(at -0.939 4.599 0)
			(layer "F.Fab")
			(effects
				(font
					(size 0.7 0.7)
					(thickness 0.15)
				)
				(justify left bottom)
			)
		)
		(fp_text user "License: Apache-2.0"
			(at -0.939 5.799 0)
			(layer "F.Fab")
			(effects
				(font
					(size 0.7 0.7)
					(thickness 0.15)
				)
				(justify left bottom)
			)
		)
		(pad "1" smd roundrect
			(at -0.48 0)
			(size 0.59 0.64)
			(layers "F.Cu" "F.Mask" "F.Paste")
			(roundrect_rratio 0.25)
			(net 370 "/USB DP Alt mode/USBC1_TX1_N")
			(pintype "passive")
		)
		(pad "2" smd roundrect
			(at 0.48 0)
			(size 0.59 0.64)
			(layers "F.Cu" "F.Mask" "F.Paste")
			(roundrect_rratio 0.25)
			(net 361 "/USB DP Alt mode/USBC1_CONN_TX1_N")
			(pintype "passive")
		)
	)
	(footprint "antmicro-footprints:R_0402_1005Metric"
		(layer "F.Cu")
		(at 66.75 85.88 -90)
		(descr "Resistor SMD 0402")
		(tags "resistor SMD 0402")
		(property "Reference" "R172"
			(at -3.7 0.45 90)
			(layer "F.SilkS")
			(effects
				(font
					(size 0.7 0.7)
					(thickness 0.15)
				)
				(justify right top)
			)
		)
		(property "Value" "R_4k7_0402"
			(at -1.011843 1.772047 90)
			(layer "F.Fab")
			(effects
				(font
					(size 0.7 0.7)
					(thickness 0.15)
				)
				(justify right top)
			)
		)
		(property "Datasheet" "https://www.bourns.com/docs/product-datasheets/cr.pdf"
			(at 0 0 90)
			(layer "F.Fab")
			(hide yes)
			(effects
				(font
					(size 1.27 1.27)
					(thickness 0.15)
				)
			)
		)
		(property "Description" "SMD Chip Resistor, 4.7 kohm, ± 1%, 62.5 mW, 0402 [1005 Metric], Thick Film, General Purpose"
			(at 0 0 90)
			(layer "F.Fab")
			(hide yes)
			(effects
				(font
					(size 1.27 1.27)
					(thickness 0.15)
				)
			)
		)
		(property "Manufacturer" "Bourns"
			(at 0 0 270)
			(unlocked yes)
			(layer "F.Fab")
			(hide yes)
			(effects
				(font
					(size 1 1)
					(thickness 0.15)
				)
			)
		)
		(property "MPN" "CR0402-FX-4701GLF"
			(at 0 0 270)
			(unlocked yes)
			(layer "F.Fab")
			(hide yes)
			(effects
				(font
					(size 1 1)
					(thickness 0.15)
				)
			)
		)
		(property "Val" "4k7"
			(at 0 0 270)
			(unlocked yes)
			(layer "F.Fab")
			(hide yes)
			(effects
				(font
					(size 1 1)
					(thickness 0.15)
				)
			)
		)
		(property "License" "Apache-2.0"
			(at 0 0 270)
			(unlocked yes)
			(layer "F.Fab")
			(hide yes)
			(effects
				(font
					(size 1 1)
					(thickness 0.15)
				)
			)
		)
		(property "Author" "Antmicro"
			(at 0 0 270)
			(unlocked yes)
			(layer "F.Fab")
			(hide yes)
			(effects
				(font
					(size 1 1)
					(thickness 0.15)
				)
			)
		)
		(property "Tolerance" "1%"
			(at 0 0 270)
			(unlocked yes)
			(layer "F.Fab")
			(hide yes)
			(effects
				(font
					(size 1 1)
					(thickness 0.15)
				)
			)
		)
		(sheetname "/CSI/")
		(sheetfile "csi.kicad_sch")
		(attr smd)
		(fp_rect
			(start -0.925 -0.47)
			(end 0.925 0.47)
			(stroke
				(width 0.05)
				(type default)
			)
			(fill no)
			(layer "F.CrtYd")
		)
		(fp_rect
			(start -0.5 -0.25)
			(end 0.5 0.25)
			(stroke
				(width 0.15)
				(type solid)
			)
			(fill no)
			(layer "F.Fab")
		)
		(fp_text user "${REFERENCE}"
			(at -0.95 3.168 90)
			(layer "F.Fab")
			(effects
				(font
					(size 0.7 0.7)
					(thickness 0.15)
				)
				(justify right top)
			)
		)
		(fp_text user "License: Apache-2.0"
			(at -0.95 5.169 90)
			(layer "F.Fab")
			(effects
				(font
					(size 0.7 0.7)
					(thickness 0.15)
				)
				(justify right top)
			)
		)
		(fp_text user "Author: Antmicro"
			(at -0.95 4.169 90)
			(layer "F.Fab")
			(effects
				(font
					(size 0.7 0.7)
					(thickness 0.15)
				)
				(justify right top)
			)
		)
		(pad "1" smd roundrect
			(at -0.48 0 270)
			(size 0.59 0.64)
			(layers "F.Cu" "F.Mask" "F.Paste")
			(roundrect_rratio 0.25)
			(net 1 "GND")
			(pintype "passive")
		)
		(pad "2" smd roundrect
			(at 0.48 0 270)
			(size 0.59 0.64)
			(layers "F.Cu" "F.Mask" "F.Paste")
			(roundrect_rratio 0.25)
			(net 995 "/CSI/CSIA_5V_ISET")
			(pintype "passive")
		)
	)
	(footprint "antmicro-footprints:R_0402_1005Metric"
		(layer "F.Cu")
		(at 156.72 114.2 180)
		(descr "Resistor SMD 0402")
		(tags "resistor SMD 0402")
		(property "Reference" "R361"
			(at -3.68 0.4 0)
			(layer "F.SilkS")
			(effects
				(font
					(size 0.7 0.7)
					(thickness 0.15)
				)
				(justify right top)
			)
		)
		(property "Value" "R_2k2_0402"
			(at -1.011843 1.772047 0)
			(layer "F.Fab")
			(effects
				(font
					(size 0.7 0.7)
					(thickness 0.15)
				)
				(justify right top)
			)
		)
		(property "Datasheet" "https://www.bourns.com/docs/product-datasheets/cr.pdf"
			(at 0 0 0)
			(layer "F.Fab")
			(hide yes)
			(effects
				(font
					(size 1.27 1.27)
					(thickness 0.15)
				)
			)
		)
		(property "Description" "SMD Chip Resistor, 2.2 kohm, ± 1%, 62.5 mW, 0402 [1005 Metric], Thick Film, General Purpose"
			(at 0 0 0)
			(layer "F.Fab")
			(hide yes)
			(effects
				(font
					(size 1.27 1.27)
					(thickness 0.15)
				)
			)
		)
		(property "MPN" "CR0402-FX-2201GLF"
			(at 0 0 180)
			(unlocked yes)
			(layer "F.Fab")
			(hide yes)
			(effects
				(font
					(size 1 1)
					(thickness 0.15)
				)
			)
		)
		(property "Manufacturer" "Bourns"
			(at 0 0 180)
			(unlocked yes)
			(layer "F.Fab")
			(hide yes)
			(effects
				(font
					(size 1 1)
					(thickness 0.15)
				)
			)
		)
		(property "License" "Apache-2.0"
			(at 0 0 180)
			(unlocked yes)
			(layer "F.Fab")
			(hide yes)
			(effects
				(font
					(size 1 1)
					(thickness 0.15)
				)
			)
		)
		(property "Author" "Antmicro"
			(at 0 0 180)
			(unlocked yes)
			(layer "F.Fab")
			(hide yes)
			(effects
				(font
					(size 1 1)
					(thickness 0.15)
				)
			)
		)
		(property "Val" "2k2"
			(at 0 0 180)
			(unlocked yes)
			(layer "F.Fab")
			(hide yes)
			(effects
				(font
					(size 1 1)
					(thickness 0.15)
				)
			)
		)
		(property "Tolerance" "1%"
			(at 0 0 180)
			(unlocked yes)
			(layer "F.Fab")
			(hide yes)
			(effects
				(font
					(size 1 1)
					(thickness 0.15)
				)
			)
		)
		(sheetname "/SoM_IO/")
		(sheetfile "som_io.kicad_sch")
		(attr smd)
		(fp_rect
			(start -0.925 -0.47)
			(end 0.925 0.47)
			(stroke
				(width 0.05)
				(type default)
			)
			(fill no)
			(layer "F.CrtYd")
		)
		(fp_rect
			(start -0.5 -0.25)
			(end 0.5 0.25)
			(stroke
				(width 0.15)
				(type solid)
			)
			(fill no)
			(layer "F.Fab")
		)
		(fp_text user "Author: Antmicro"
			(at -0.95 4.169 0)
			(layer "F.Fab")
			(effects
				(font
					(size 0.7 0.7)
					(thickness 0.15)
				)
				(justify right top)
			)
		)
		(fp_text user "License: Apache-2.0"
			(at -0.95 5.169 0)
			(layer "F.Fab")
			(effects
				(font
					(size 0.7 0.7)
					(thickness 0.15)
				)
				(justify right top)
			)
		)
		(fp_text user "${REFERENCE}"
			(at -0.95 3.168 0)
			(layer "F.Fab")
			(effects
				(font
					(size 0.7 0.7)
					(thickness 0.15)
				)
				(justify right top)
			)
		)
		(pad "1" smd roundrect
			(at -0.48 0 180)
			(size 0.59 0.64)
			(layers "F.Cu" "F.Mask" "F.Paste")
			(roundrect_rratio 0.25)
			(net 2 "+3V3")
			(pintype "passive")
		)
		(pad "2" smd roundrect
			(at 0.48 0 180)
			(size 0.59 0.64)
			(layers "F.Cu" "F.Mask" "F.Paste")
			(roundrect_rratio 0.25)
			(net 43 "/Peripherals/I2C_{CONN}.SDA")
			(pintype "passive")
		)
	)
	(footprint "antmicro-footprints:C_0805_2012Metric"
		(layer "F.Cu")
		(at 167.7 93.32 -90)
		(descr "Capacitor SMD 0805")
		(tags "capacitor SMD 0805")
		(property "Reference" "C300"
			(at 1.745 0.425 90)
			(layer "F.SilkS")
			(effects
				(font
					(size 0.7 0.7)
					(thickness 0.15)
				)
				(justify right top)
			)
		)
		(property "Value" "C_22u_25V_0805"
			(at -2.055717 1.963152 90)
			(layer "F.Fab")
			(effects
				(font
					(size 0.7 0.7)
					(thickness 0.15)
				)
				(justify right top)
			)
		)
		(property "Datasheet" "https://product.samsungsem.com/mlcc/CL21A226MAYNNN.do"
			(at 0 0 90)
			(layer "F.Fab")
			(hide yes)
			(effects
				(font
					(size 1.27 1.27)
					(thickness 0.15)
				)
			)
		)
		(property "Description" "SMT Multilayer Ceramic Capacitor, 22uF, +/-20%, 25V, X5R, 0805 [2012 Metric]"
			(at 0 0 90)
			(layer "F.Fab")
			(hide yes)
			(effects
				(font
					(size 1.27 1.27)
					(thickness 0.15)
				)
			)
		)
		(property "MPN" "CL21A226MAYNNNE"
			(at 0 0 270)
			(unlocked yes)
			(layer "F.Fab")
			(hide yes)
			(effects
				(font
					(size 1 1)
					(thickness 0.15)
				)
			)
		)
		(property "Manufacturer" "Samsung Electro-Mechanics"
			(at 0 0 270)
			(unlocked yes)
			(layer "F.Fab")
			(hide yes)
			(effects
				(font
					(size 1 1)
					(thickness 0.15)
				)
			)
		)
		(property "License" "Apache-2.0"
			(at 0 0 270)
			(unlocked yes)
			(layer "F.Fab")
			(hide yes)
			(effects
				(font
					(size 1 1)
					(thickness 0.15)
				)
			)
		)
		(property "Author" "Antmicro"
			(at 0 0 270)
			(unlocked yes)
			(layer "F.Fab")
			(hide yes)
			(effects
				(font
					(size 1 1)
					(thickness 0.15)
				)
			)
		)
		(property "Val" "22u"
			(at 0 0 270)
			(unlocked yes)
			(layer "F.Fab")
			(hide yes)
			(effects
				(font
					(size 1 1)
					(thickness 0.15)
				)
			)
		)
		(property "Voltage" "25V"
			(at 0 0 270)
			(unlocked yes)
			(layer "F.Fab")
			(hide yes)
			(effects
				(font
					(size 1 1)
					(thickness 0.15)
				)
			)
		)
		(property "Dielectric" "X5R"
			(at 0 0 270)
			(unlocked yes)
			(layer "F.Fab")
			(hide yes)
			(effects
				(font
					(size 1 1)
					(thickness 0.15)
				)
			)
		)
		(property "Public" "False"
			(at 0 0 270)
			(unlocked yes)
			(layer "F.Fab")
			(hide yes)
			(effects
				(font
					(size 1 1)
					(thickness 0.15)
				)
			)
		)
		(component_classes
			(class "DCDC_SOM")
		)
		(sheetname "/DCDC/")
		(sheetfile "dcdc.kicad_sch")
		(attr smd)
		(fp_line
			(start -0.3 0.7)
			(end 0.3 0.7)
			(stroke
				(width 0.15)
				(type solid)
			)
			(layer "F.SilkS")
		)
		(fp_line
			(start -0.3 -0.7)
			(end 0.3 -0.7)
			(stroke
				(width 0.15)
				(type solid)
			)
			(layer "F.SilkS")
		)
		(fp_rect
			(start 1.95 -0.9)
			(end -1.95 0.9)
			(stroke
				(width 0.05)
				(type default)
			)
			(fill no)
			(layer "F.CrtYd")
		)
		(fp_rect
			(start -0.95 -0.675)
			(end 0.95 0.675)
			(stroke
				(width 0.15)
				(type solid)
			)
			(fill no)
			(layer "F.Fab")
		)
		(fp_text user "${REFERENCE}"
			(at -1.9 3.947 90)
			(layer "F.Fab")
			(effects
				(font
					(size 0.7 0.7)
					(thickness 0.15)
				)
				(justify right top)
			)
		)
		(fp_text user "Author: Antmicro"
			(at -1.9 5.947 90)
			(layer "F.Fab")
			(effects
				(font
					(size 0.7 0.7)
					(thickness 0.15)
				)
				(justify right top)
			)
		)
		(fp_text user "License: Apache-2.0"
			(at -1.9 4.947 90)
			(layer "F.Fab")
			(effects
				(font
					(size 0.7 0.7)
					(thickness 0.15)
				)
				(justify right top)
			)
		)
		(pad "1" smd roundrect
			(at -1.1 0 270)
			(size 1.2 1.3)
			(layers "F.Cu" "F.Mask" "F.Paste")
			(roundrect_rratio 0.25)
			(net 1 "GND")
			(pintype "passive")
		)
		(pad "2" smd roundrect
			(at 1.1 0 270)
			(size 1.2 1.3)
			(layers "F.Cu" "F.Mask" "F.Paste")
			(roundrect_rratio 0.25)
			(net 903 "/DCDC/16V_OUT")
			(pintype "passive")
		)
	)
	(footprint "antmicro-footprints:C_0402_1005Metric"
		(layer "F.Cu")
		(at 203.6 133.7 90)
		(descr "Capacitor SMD 0402")
		(tags "capacitor SMD 0402")
		(property "Reference" "C86"
			(at -1.2 -0.5 90)
			(layer "F.SilkS")
			(effects
				(font
					(size 0.7 0.7)
					(thickness 0.15)
				)
				(justify left bottom)
			)
		)
		(property "Value" "C_100n_0402"
			(at -1.022927 2.155213 90)
			(layer "F.Fab")
			(effects
				(font
					(size 0.7 0.7)
					(thickness 0.15)
				)
				(justify left bottom)
			)
		)
		(property "Datasheet" "https://www.murata.com/products/productdetail?partno=GRM155R61H104KE14%23"
			(at 0 0 90)
			(layer "F.Fab")
			(hide yes)
			(effects
				(font
					(size 1.27 1.27)
					(thickness 0.15)
				)
			)
		)
		(property "Description" "SMD Multilayer Ceramic Capacitor, 0.1 µF, 50 V, 0402 [1005 Metric], ± 10%, X5R, GRM Series"
			(at 0 0 90)
			(layer "F.Fab")
			(hide yes)
			(effects
				(font
					(size 1.27 1.27)
					(thickness 0.15)
				)
			)
		)
		(property "MPN" "GRM155R61H104KE14D"
			(at 0 0 90)
			(unlocked yes)
			(layer "F.Fab")
			(hide yes)
			(effects
				(font
					(size 1 1)
					(thickness 0.15)
				)
			)
		)
		(property "Val" "100n"
			(at 0 0 90)
			(unlocked yes)
			(layer "F.Fab")
			(hide yes)
			(effects
				(font
					(size 1 1)
					(thickness 0.15)
				)
			)
		)
		(property "Voltage" "50V"
			(at 0 0 90)
			(unlocked yes)
			(layer "F.Fab")
			(hide yes)
			(effects
				(font
					(size 1 1)
					(thickness 0.15)
				)
			)
		)
		(property "Dielectric" "X5R"
			(at 0 0 90)
			(unlocked yes)
			(layer "F.Fab")
			(hide yes)
			(effects
				(font
					(size 1 1)
					(thickness 0.15)
				)
			)
		)
		(property "Manufacturer" "Murata"
			(at 0 0 90)
			(unlocked yes)
			(layer "F.Fab")
			(hide yes)
			(effects
				(font
					(size 1 1)
					(thickness 0.15)
				)
			)
		)
		(property "License" "Apache-2.0"
			(at 0 0 90)
			(unlocked yes)
			(layer "F.Fab")
			(hide yes)
			(effects
				(font
					(size 1 1)
					(thickness 0.15)
				)
			)
		)
		(property "Author" "Antmicro"
			(at 0 0 90)
			(unlocked yes)
			(layer "F.Fab")
			(hide yes)
			(effects
				(font
					(size 1 1)
					(thickness 0.15)
				)
			)
		)
		(sheetname "/USB Hub/")
		(sheetfile "usb_hub.kicad_sch")
		(attr smd)
		(fp_rect
			(start -0.925 -0.47)
			(end 0.925 0.47)
			(stroke
				(width 0.05)
				(type default)
			)
			(fill no)
			(layer "F.CrtYd")
		)
		(fp_line
			(start 0.504 -0.25)
			(end 0.504 0.248)
			(stroke
				(width 0.15)
				(type solid)
			)
			(layer "F.Fab")
		)
		(fp_line
			(start -0.494 -0.25)
			(end 0.504 -0.25)
			(stroke
				(width 0.15)
				(type solid)
			)
			(layer "F.Fab")
		)
		(fp_line
			(start 0.504 0.248)
			(end -0.494 0.248)
			(stroke
				(width 0.15)
				(type solid)
			)
			(layer "F.Fab")
		)
		(fp_line
			(start -0.494 0.248)
			(end -0.494 -0.25)
			(stroke
				(width 0.15)
				(type solid)
			)
			(layer "F.Fab")
		)
		(fp_text user "${REFERENCE}"
			(at -0.939 4.599 90)
			(layer "F.Fab")
			(effects
				(font
					(size 0.7 0.7)
					(thickness 0.15)
				)
				(justify left bottom)
			)
		)
		(fp_text user "License: Apache-2.0"
			(at -0.939 5.799 90)
			(layer "F.Fab")
			(effects
				(font
					(size 0.7 0.7)
					(thickness 0.15)
				)
				(justify left bottom)
			)
		)
		(fp_text user "Author: Antmicro"
			(at -0.939 3.399 90)
			(layer "F.Fab")
			(effects
				(font
					(size 0.7 0.7)
					(thickness 0.15)
				)
				(justify left bottom)
			)
		)
		(pad "1" smd roundrect
			(at -0.48 0 90)
			(size 0.59 0.64)
			(layers "F.Cu" "F.Mask" "F.Paste")
			(roundrect_rratio 0.25)
			(net 1 "GND")
			(pintype "passive")
		)
		(pad "2" smd roundrect
			(at 0.48 0 90)
			(size 0.59 0.64)
			(layers "F.Cu" "F.Mask" "F.Paste")
			(roundrect_rratio 0.25)
			(net 282 "+1V15")
			(pintype "passive")
		)
	)
)
